FILE_TYPE = CONNECTIVITY;
{Allegro Design Entry HDL 17.2-2016 S081 (4005846) 1/11/2022}
"PAGE_NUMBER" = 154;
0"NC";
1"P3V3_AUX\g";
2"P3V3_AUX\g";
3"P3V3_AUX\g";
4"P3V3_AUX\g";
5"P3V3_OCP_SFF\g";
6"P3V3_AUX\g";
7"P3V3_AUX\g";
8"P3V3_AUX\g";
9"P3V3_AUX\g";
10"P3V3_AUX\g";
11"P3V3_AUX\g";
12"GND\g";
13"GND\g";
14"GND\g";
15"GND\g";
16"GND\g";
17"GND\g";
18"GND\g";
19"GND\g";
20"GND\g";
21"GND\g";
22"GND\g";
23"GND\g";
24"GND\g";
25"GND\g";
26"GND\g";
27"GND\g";
28"HP_OCP_V3_1_EN"$PHYS_NET_NAME"RST_PCIE_M2_N"CDS_PHYS_NET_NAME"HP_OCP_V3_1_EN";
29"TP_PCA9555_0_P6"$PHYS_NET_NAME"RST_PCIE_M2_N"CDS_PHYS_NET_NAME"TP_PCA9555_0_P06";
30"TP_PCA9555_0_P7"$PHYS_NET_NAME"RST_PCIE_M2_N"CDS_PHYS_NET_NAME"TP_PCA9555_0_P06";
31"TP_PCA9555_0_P10"$PHYS_NET_NAME"RST_PCIE_M2_N"CDS_PHYS_NET_NAME"TP_PCA9555_0_P06";
32"TP_PCA9555_0_P11"$PHYS_NET_NAME"RST_PCIE_M2_N"CDS_PHYS_NET_NAME"TP_PCA9555_0_P06";
33"TP_PCA9555_0_P12"$PHYS_NET_NAME"RST_PCIE_M2_N"CDS_PHYS_NET_NAME"TP_PCA9555_0_P06";
34"TP_PCA9555_0_P13"$PHYS_NET_NAME"RST_PCIE_M2_N"CDS_PHYS_NET_NAME"TP_PCA9555_0_P06";
35"TP_PCA9555_0_P5"$PHYS_NET_NAME"RST_PCIE_M2_N"CDS_PHYS_NET_NAME"HP_LVC3_OCP_V3_1_FAULT_N";
36"HP_LVC3_OCP_V3_1_PRSNT2_N"$PHYS_NET_NAME"RST_PCIE_M2_N"CDS_PHYS_NET_NAME"HP_LVC3_OCP_V3_1_PRSNT2_N";
37"HP_LVC3_OCP_V3_1_ATTN_OUT_SW_N"$PHYS_NET_NAME"RST_PCIE_M2_N"CDS_PHYS_NET_NAME"HP_LVC3_OCP_V3_1_ATTN_OUT_SW_N";
38"TP_PCA9555_0_P01"$PHYS_NET_NAME"RST_PCIE_M2_N"CDS_PHYS_NET_NAME"TP_PCA9555_0_P06";
39"TP_PCA9555_0_P00"$PHYS_NET_NAME"RST_PCIE_M2_N"CDS_PHYS_NET_NAME"TP_PCA9555_0_P06";
40"TP_PCA9555_0_P14"$PHYS_NET_NAME"RST_PCIE_M2_N"CDS_PHYS_NET_NAME"TP_PCA9555_0_P06";
41"TP_PCA9555_0_P15"$PHYS_NET_NAME"RST_PCIE_M2_N"CDS_PHYS_NET_NAME"TP_PCA9555_0_P06";
42"SMB_PEHPCPU0_LVC3_SDA"$PHYS_NET_NAME"RST_PCIE_M2_N"CDS_PHYS_NET_NAME"SMB_PEHPCPU0_LVC3_SDA";
43"OCP_SFF_AUX_PWR_PLD_EN_R"$PHYS_NET_NAME"RST_PCIE_M2_N"CDS_PHYS_NET_NAME"HP_LVC3_OCP_V3_1_PWRGD";
44"OCP_SFF_AUX_PWR_EN_R2"$PHYS_NET_NAME"RST_PCIE_M2_N"CDS_PHYS_NET_NAME"HP_LVC3_OCP_V3_1_PWRGD";
45"HP_LVC3_OCP_V3_1_PWRGD_R2"$PHYS_NET_NAME"RST_PCIE_M2_N"CDS_PHYS_NET_NAME"HP_LVC3_OCP_V3_1_PWRGD";
46"RST_HP_OCP_V3_1_N"$PHYS_NET_NAME"RST_PCIE_M2_N"CDS_PHYS_NET_NAME"RST_HP_OCP_V3_1_N";
47"HP_LVC3_OCP_V3_1_EN"$PHYS_NET_NAME"RST_PCIE_M2_N"CDS_PHYS_NET_NAME"HP_LVC3_OCP_V3_1_EN";
48"HP_OCP_V3_1_RST"$PHYS_NET_NAME"RST_PCIE_M2_N"CDS_PHYS_NET_NAME"HP_LVC3_OCP_V3_1_HSC_PWRGD";
49"OCP_SFF_AUX_PWR_PLD_EN"$PHYS_NET_NAME"RST_PCIE_M2_N"CDS_PHYS_NET_NAME"HP_LVC3_OCP_V3_1_PWRGD";
50"HP_LVC3_OCP_V3_1_PWRGD_R"$PHYS_NET_NAME"RST_PCIE_M2_N"CDS_PHYS_NET_NAME"HP_LVC3_OCP_V3_1_PWRGD";
51"HP_LVC3_OCP_V3_1_PWRGD_R"$PHYS_NET_NAME"RST_PCIE_M2_N"CDS_PHYS_NET_NAME"HP_LVC3_OCP_V3_1_PWRGD";
52"OCP_SFF_AUX_PWR_EN"$PHYS_NET_NAME"RST_PCIE_M2_N"CDS_PHYS_NET_NAME"HP_LVC3_OCP_V3_1_PWRGD";
53"PD_SMB_OCP1_HP_ADD2"$PHYS_NET_NAME"RST_PCIE_M2_N"CDS_PHYS_NET_NAME"PD_SMB_OCP1_HP_ADD2";
54"PD_SMB_OCP1_HP_ADD1"$PHYS_NET_NAME"RST_PCIE_M2_N"CDS_PHYS_NET_NAME"PD_SMB_OCP1_HP_ADD1";
55"PD_SMB_OCP1_HP_ADD0"$PHYS_NET_NAME"RST_PCIE_M2_N"CDS_PHYS_NET_NAME"PD_SMB_OCP1_HP_ADD0";
56"FM_SMB_CPU0_ALERT"$PHYS_NET_NAME"RST_PCIE_M2_N"CDS_PHYS_NET_NAME"FM_SMB_CPU0_ALERT";
57"TP_PCA9555_0_P17"$PHYS_NET_NAME"RST_PCIE_M2_N"CDS_PHYS_NET_NAME"TP_PCA9555_0_P06";
58"HP_LVC3_OCP_V3_1_PWRGD"$PHYS_NET_NAME"RST_PCIE_M2_N"CDS_PHYS_NET_NAME"HP_LVC3_OCP_V3_1_PWRGD";
59"HP_LVC3_OCP_V3_1_P12V_PWRGD"$PHYS_NET_NAME"RST_PCIE_M2_N"CDS_PHYS_NET_NAME"HP_LVC3_OCP_V3_1_HSC_PWRGD";
60"SMB_PEHPCPU0_LVC3_SCL"$PHYS_NET_NAME"RST_PCIE_M2_N"CDS_PHYS_NET_NAME"SMB_PEHPCPU0_LVC3_SCL";
61"OCP_V3_1_P3V3_PWRGD";
62"SMB_PEHPCPU0_LVC3_R_SDA"$PHYS_NET_NAME"RST_PCIE_M2_N"CDS_PHYS_NET_NAME"SMB_PEHPCPU0_LVC3_R_SDA";
63"SMB_PEHPCPU0_LVC3_R_SCL"$PHYS_NET_NAME"RST_PCIE_M2_N"CDS_PHYS_NET_NAME"SMB_PEHPCPU0_LVC3_R_SCL";
64"HP_LVC3_OCP_V3_1_PRSNT2"$PHYS_NET_NAME"RST_PCIE_M2_N"CDS_PHYS_NET_NAME"HP_LVC3_OCP_V3_1_PRSNT2";
65"HP_LVC3_OCP_V3_1_PRSNT2_N"$PHYS_NET_NAME"RST_PCIE_M2_N"CDS_PHYS_NET_NAME"HP_LVC3_OCP_V3_1_PRSNT2_N";
66"HP_OCP_V3_1_EN"$PHYS_NET_NAME"RST_PCIE_M2_N"CDS_PHYS_NET_NAME"HP_OCP_V3_1_EN";
67"TP_PCA9555_0_P16"$PHYS_NET_NAME"RST_PCIE_M2_N"CDS_PHYS_NET_NAME"TP_PCA9555_0_P06";
68"FM_SMB_CPU0_ALERT"CDS_PHYS_NET_NAME"FM_SMB_CPU0_ALERT";
69"RST_OCP_V3_1_N"$PHYS_NET_NAME"RST_PCIE_M2_N"CDS_PHYS_NET_NAME"RST_OCP_V3_1_N";
70"FM_SMB_PEHPCPU0_PCIE_ALERT_N"CDS_PHYS_NET_NAME"FM_SMB_PEHPCPU0_PCIE_ALERT_N";
71"SMB_PEHPCPU0_LVC3_R_SDA"$PHYS_NET_NAME"RST_PCIE_M2_N"CDS_PHYS_NET_NAME"SMB_PEHPCPU0_LVC3_R_SDA";
72"SMB_PEHPCPU0_LVC3_R_SCL"$PHYS_NET_NAME"RST_PCIE_M2_N"CDS_PHYS_NET_NAME"SMB_PEHPCPU0_LVC3_R_SCL";
73"HP_OCP_V3_1_RST_R"$PHYS_NET_NAME"RST_PCIE_M2_N"CDS_PHYS_NET_NAME"HP_LVC3_OCP_V3_1_HSC_PWRGD";
%"UNIVERSAL_GND"
"1","(-1900,8625)","0","logical_power","I126";
;
HDL_POWER"GND"
CDS_LIB"logical_power";
"A"21;
%"Q_RES"
"1","(-2800,8300)","0","pure_quanta","I130";
;
PART_NUMBER"CS03322FB03"
WATTAGE"1/16W"
VALUE"33.2"
PACK_TYPE"0402LF"
TOLERANCE"1%"
MATERIAL"CHIP"
$LOCATION"R1130"
CDS_LIB"pure_quanta"
CDS_LOCATION"R1130"
$SEC"1"
CDS_SEC"1";
"B"
$PN"2"72;
"A"
$PN"1"60;
%"Q_RES"
"1","(-2800,8250)","0","pure_quanta","I131";
;
PART_NUMBER"CS03322FB03"
TOLERANCE"1%"
PACK_TYPE"0402LF"
VALUE"33.2"
$LOCATION"R1131"
CDS_LIB"pure_quanta"
WATTAGE"1/16W"
MATERIAL"CHIP"
CDS_LOCATION"R1131"
$SEC"1"
CDS_SEC"1";
"B"
$PN"2"71;
"A"
$PN"1"42;
%"Q_RES"
"1","(-2800,8200)","0","pure_quanta","I132";
;
PART_NUMBER"CS03322FB03"
PACK_TYPE"0402LF"
TOLERANCE"1%"
VALUE"33.2"
$LOCATION"R1921"
WATTAGE"1/16W"
MATERIAL"CHIP"
CDS_LIB"pure_quanta"
CDS_LOCATION"R1921"
$SEC"1"
CDS_SEC"1";
"B"
$PN"2"70;
"A"
$PN"1"68;
%"Q_RES"
"2","(-4325,9600)","0","pure_quanta","I133";
;
PART_NUMBER"CS21002FB06"
TOLERANCE"1%"
VALUE"1K"
MATERIAL"EMPTY"
WATTAGE"1/16W"
PACK_TYPE"0402LF"
$LOCATION"R1127"
CDS_LIB"pure_quanta"
CDS_LOCATION"R1127"
$SEC"1"
CDS_SEC"1";
"A"
$PN"1"10;
"B"
$PN"2"55;
%"Q_RES"
"2","(-4575,9600)","0","pure_quanta","I134";
;
PART_NUMBER"CS21002FB06"
VALUE"1K"
TOLERANCE"1%"
WATTAGE"1/16W"
MATERIAL"EMPTY"
PACK_TYPE"0402LF"
$LOCATION"R3037"
CDS_LIB"pure_quanta"
CDS_LOCATION"R3037"
$SEC"1"
CDS_SEC"1";
"A"
$PN"1"10;
"B"
$PN"2"54;
%"Q_RES"
"2","(-4325,9000)","0","pure_quanta","I137";
;
PART_NUMBER"CS21002FB06"
PACK_TYPE"0402LF"
TOLERANCE"1%"
MATERIAL"CHIP"
WATTAGE"1/16W"
VALUE"1K"
$LOCATION"R1128"
CDS_LIB"pure_quanta"
CDS_LOCATION"R1128"
$SEC"1"
CDS_SEC"1";
"A"
$PN"1"55;
"B"
$PN"2"17;
%"UNIVERSAL_GND"
"1","(-4325,8775)","0","logical_power","I138";
;
CDS_LIB"logical_power"
HDL_POWER"GND";
"A"17;
%"UNIVERSAL_GND"
"1","(-4575,8775)","0","logical_power","I139";
;
CDS_LIB"logical_power"
HDL_POWER"GND";
"A"18;
%"Q_RES"
"2","(-4575,9000)","0","pure_quanta","I140";
;
PART_NUMBER"CS21002FB06"
PACK_TYPE"0402LF"
MATERIAL"CHIP"
TOLERANCE"1%"
VALUE"1K"
WATTAGE"1/16W"
$LOCATION"R1126"
CDS_LIB"pure_quanta"
CDS_LOCATION"R1126"
$SEC"1"
CDS_SEC"1";
"A"
$PN"1"54;
"B"
$PN"2"18;
%"UNIVERSAL_POWER"
"1","(-4825,10000)","0","logical_power","I141";
;
HDL_POWER"P3V3_AUX"
CDS_LIB"logical_power";
"A"10;
%"Q_RES"
"2","(-4825,9600)","0","pure_quanta","I142";
;
PART_NUMBER"CS21002FB06"
TOLERANCE"1%"
VALUE"1K"
WATTAGE"1/16W"
MATERIAL"EMPTY"
PACK_TYPE"0402LF"
$LOCATION"R1123"
CDS_LIB"pure_quanta"
CDS_LOCATION"R1123"
$SEC"1"
CDS_SEC"1";
"A"
$PN"1"10;
"B"
$PN"2"53;
%"Q_RES"
"2","(-4825,9000)","0","pure_quanta","I143";
;
PART_NUMBER"CS21002FB06"
TOLERANCE"1%"
PACK_TYPE"0402LF"
WATTAGE"1/16W"
MATERIAL"CHIP"
VALUE"1K"
$LOCATION"R1124"
CDS_LIB"pure_quanta"
CDS_LOCATION"R1124"
$SEC"1"
CDS_SEC"1";
"A"
$PN"1"53;
"B"
$PN"2"19;
%"UNIVERSAL_GND"
"1","(-4825,8775)","0","logical_power","I144";
;
CDS_LIB"logical_power"
HDL_POWER"GND";
"A"19;
%"UNIVERSAL_POWER"
"1","(3175,7525)","0","logical_power","I145";
;
HDL_POWER"P3V3_AUX"
CDS_LIB"logical_power";
"A"9;
%"Q_CAP"
"1","(3175,7250)","0","pure_quanta","I148";
;
PART_NUMBER"CH4104K1B00"
PACK_TYPE"0402"
VALUE"0.1UF"
VOLTAGE"25V"
TOLERANCE"10%"
MATERIAL"X7R"
$LOCATION"C581"
CDS_LIB"pure_quanta"
CDS_LOCATION"C581"
$SEC"1"
CDS_SEC"1";
"B"
$PN"2"16;
"A"
$PN"1"9;
%"UNIVERSAL_GND"
"1","(3175,7025)","0","logical_power","I149";
;
CDS_LIB"logical_power"
HDL_POWER"GND";
"A"16;
%"UNIVERSAL_GND"
"1","(2050,6750)","0","logical_power","I151";
;
CDS_LIB"logical_power"
HDL_POWER"GND";
"A"27;
%"UNIVERSAL_POWER"
"1","(-2350,5775)","0","logical_power","I168";
;
HDL_POWER"P3V3_AUX"
CDS_LIB"logical_power";
"A"4;
%"Q_CAP"
"1","(-2350,5500)","0","pure_quanta","I169";
;
PART_NUMBER"CH4104K1B00"
PACK_TYPE"0402"
MATERIAL"X7R"
VALUE"0.1UF"
TOLERANCE"10%"
VOLTAGE"25V"
$LOCATION"C578"
CDS_LIB"pure_quanta"
CDS_LOCATION"C578"
$SEC"1"
CDS_SEC"1";
"B"
$PN"2"22;
"A"
$PN"1"4;
%"UNIVERSAL_GND"
"1","(-2350,5275)","0","logical_power","I170";
;
HDL_POWER"GND"
CDS_LIB"logical_power";
"A"22;
%"UNIVERSAL_POWER"
"1","(-4000,5725)","0","logical_power","I171";
;
HDL_POWER"P3V3_AUX"
CDS_LIB"logical_power";
"A"11;
%"Q_RES"
"2","(-4000,5450)","0","pure_quanta","I172";
;
PART_NUMBER"CS21002FB06"
TOLERANCE"1%"
WATTAGE"1/16W"
MATERIAL"CHIP"
VALUE"1K"
PACK_TYPE"0402LF"
$LOCATION"R1129"
CDS_LIB"pure_quanta"
CDS_LOCATION"R1129"
$SEC"1"
CDS_SEC"1";
"A"
$PN"1"11;
"B"
$PN"2"64;
%"UNIVERSAL_GND"
"1","(-3225,4900)","0","logical_power","I174";
;
HDL_POWER"GND"
CDS_LIB"logical_power";
"A"23;
%"UNIVERSAL_GND"
"1","(-4000,4525)","0","logical_power","I176";
;
HDL_POWER"GND"
CDS_LIB"logical_power";
"A"24;
%"MOSFET_N"
"1","(-4050,4900)","0","pure_quanta","I177";
;
PART_NUMBER"BAM138K0000"
VALUE"BSS138K"
MATERIAL"IC"
$LOCATION"U49"
MANUF_PN"BSS138K"
CDS_LMAN_SYM_OUTLINE"-50,50,100,-150"
CDS_LIB"pure_quanta"
PACK_TYPE"SMLF"
CDS_LOCATION"U49"
$SEC"1"
CDS_SEC"1";
"GATE"
$PN"G"65;
"SOURCE"
$PN"S"24;
"DRAIN"
$PN"D"64;
%"74LVC1G08W57"
"1","(2400,6975)","0","pure_quanta","I189";
;
PART_NUMBER"AL1G0008020"
MATERIAL"IC"
VALUE"74LVC1G08W5-7"
PART_TYPE"SMLF"
$LOCATION"U210"
CDS_LIB"pure_quanta"
NEEDS_NO_SIZE"TRUE"
CDS_LMAN_SYM_OUTLINE"-150,150,150,-150"
CDS_LOCATION"U210"
$SEC"1"
CDS_SEC"1";
"VCC"
$PN"5"9;
"Y"
$PN"4"46;
"GND"
$PN"3"27;
"B"
$PN"2"69;
"A"
$PN"1"51;
%"74LVC1G08W57"
"1","(-2925,5125)","0","pure_quanta","I190";
;
PART_NUMBER"AL1G0008020"
VALUE"74LVC1G08W5-7"
PART_TYPE"SMLF"
MATERIAL"IC"
$LOCATION"U208"
NEEDS_NO_SIZE"TRUE"
CDS_LMAN_SYM_OUTLINE"-150,150,150,-150"
CDS_LIB"pure_quanta"
CDS_LOCATION"U208"
$SEC"1"
CDS_SEC"1";
"VCC"
$PN"5"4;
"Y"
$PN"4"47;
"GND"
$PN"3"23;
"B"
$PN"2"64;
"A"
$PN"1"66;
%"Q_CAP"
"1","(-2475,9900)","0","pure_quanta","I192";
;
PART_NUMBER"CH4104K1B00"
MATERIAL"X7R"
TOLERANCE"10%"
VOLTAGE"25V"
PACK_TYPE"0402"
VALUE"0.1UF"
$LOCATION"C579"
CDS_LIB"pure_quanta"
CDS_LOCATION"C579"
$SEC"1"
CDS_SEC"1";
"B"
$PN"2"20;
"A"
$PN"1"2;
%"UNIVERSAL_GND"
"1","(-2475,9675)","0","logical_power","I193";
;
HDL_POWER"GND"
CDS_LIB"logical_power";
"A"20;
%"UNIVERSAL_POWER"
"1","(-2475,10175)","0","logical_power","I194";
;
HDL_POWER"P3V3_AUX"
CDS_LIB"logical_power";
"A"2;
%"PCA9555APW"
"1","(-1425,9250)","0","pure_quanta","I206";
;
PART_NUMBER"AL009555K07"
MATERIAL"IC"
PART_TYPE"SMLF"
VALUE"PCA9555APW"
LOCATION"U209"
NEEDS_NO_SIZE"TRUE"
SEC_TYPE""
CDS_LMAN_SYM_OUTLINE"-225,500,225,-500"
CDS_LIB"pure_quanta"
SEC"1";
"A2"
$PN"3"53;
"A1"
$PN"2"54;
"A0"
$PN"21"55;
"P1_7"
$PN"20"57;
"P1_6"
$PN"19"67;
"P1_5"
$PN"18"41;
"P1_4"
$PN"17"40;
"P1_3"
$PN"16"34;
"P1_2"
$PN"15"33;
"P1_1"
$PN"14"32;
"P1_0"
$PN"13"31;
"P0_7"
$PN"11"30;
"P0_6"
$PN"10"29;
"P0_5"
$PN"9"35;
"P0_4"
$PN"8"36;
"P0_3"
$PN"7"37;
"P0_2"
$PN"6"28;
"P0_1"
$PN"5"38;
"P0_0"
$PN"4"39;
"SCL"
$PN"22"63;
"SDA"
$PN"23"62;
"INT# \B"
$PN"1"56;
"VSS"
$PN"12"21;
"VDD"
$PN"24"2;
%"74LVC1G08W57"
"1","(-125,7125)","0","pure_quanta","I221";
;
PART_NUMBER"AL1G0008020"
MATERIAL"IC"
PART_TYPE"SMLF"
VALUE"74LVC1G08W5-7"
$LOCATION"U322"
CDS_LMAN_SYM_OUTLINE"-150,150,150,-150"
NEEDS_NO_SIZE"TRUE"
CDS_LIB"pure_quanta"
CDS_LOCATION"U322"
$SEC"1"
CDS_SEC"1";
"VCC"
$PN"5"8;
"Y"
$PN"4"58;
"GND"
$PN"3"14;
"B"
$PN"2"59;
"A"
$PN"1"73;
%"UNIVERSAL_POWER"
"1","(425,7900)","0","logical_power","I222";
;
HDL_POWER"P3V3_AUX"
CDS_LIB"logical_power";
"A"8;
%"Q_CAP"
"1","(425,7625)","0","pure_quanta","I223";
;
PART_NUMBER"CH4104K1B00"
VOLTAGE"25V"
PACK_TYPE"0402"
MATERIAL"X7R"
TOLERANCE"10%"
VALUE"0.1UF"
$LOCATION"C2346"
CDS_LIB"pure_quanta"
CDS_LOCATION"C2346"
$SEC"1"
CDS_SEC"1";
"B"
$PN"2"15;
"A"
$PN"1"8;
%"UNIVERSAL_GND"
"1","(425,7400)","0","logical_power","I224";
;
HDL_POWER"GND"
CDS_LIB"logical_power";
"A"15;
%"UNIVERSAL_GND"
"1","(-475,6900)","0","logical_power","I225";
;
HDL_POWER"GND"
CDS_LIB"logical_power";
"A"14;
%"UNIVERSAL_GND"
"1","(-2975,7300)","0","logical_power","I226";
;
HDL_POWER"GND"
CDS_LIB"logical_power";
"A"25;
%"UNIVERSAL_POWER"
"1","(-4175,7475)","0","logical_power","I227";
;
HDL_POWER"P3V3_OCP_SFF"
CDS_LIB"logical_power";
"A"5;
%"APX80929SAG7"
"1","(-3475,7325)","2","pure_quanta","I228";
;
PART_NUMBER"AL080929000"
PART_TYPE"SMLF"
VALUE"APX809-29SAG-7"
MATERIAL"IC"
LOCATION"U52"
CDS_LMAN_SYM_OUTLINE"-225,200,225,-200"
NEEDS_NO_SIZE"TRUE"
CDS_LIB"pure_quanta"
$SEC"1"
CDS_SEC"1";
"GND"
$PN"1"25;
"RESET_L \B"
$PN"2"48;
"VCC"
$PN"3"5;
%"Q_CAP"
"1","(-4175,7150)","2","pure_quanta","I229";
;
PART_NUMBER"CH4104K1B00"
VOLTAGE"25V"
VALUE"0.1UF"
MATERIAL"X7R"
PACK_TYPE"0402"
TOLERANCE"10%"
LOCATION"C580"
CDS_LIB"pure_quanta"
$SEC"1"
CDS_SEC"1";
"B"
$PN"2"26;
"A"
$PN"1"5;
%"UNIVERSAL_GND"
"1","(-4175,6925)","0","logical_power","I230";
;
HDL_POWER"GND"
CDS_LIB"logical_power";
"A"26;
%"Q_RES"
"1","(-1900,7550)","0","pure_quanta","I232";
;
PART_NUMBER"CS00002JB13"
MATERIAL"EMPTY"
PACK_TYPE"0402LF"
VALUE"0"
TOLERANCE"5%"
$LOCATION"R4613"
CDS_LIB"pure_quanta"
WATTAGE"1/16W"
CDS_LOCATION"R4613"
$SEC"1"
CDS_SEC"1";
"B"
$PN"2"73;
"A"
$PN"1"61;
%"Q_RES"
"2","(-1325,7800)","0","pure_quanta","I235";
;
PART_NUMBER"CS21002FB06"
WATTAGE"1/16W"
TOLERANCE"1%"
VALUE"1K"
MATERIAL"EMPTY"
PACK_TYPE"0402LF"
$LOCATION"R3160"
CDS_LIB"pure_quanta"
CDS_LOCATION"R3160"
$SEC"1"
CDS_SEC"1";
"A"
$PN"1"7;
"B"
$PN"2"73;
%"UNIVERSAL_POWER"
"1","(-1325,8025)","0","logical_power","I236";
;
HDL_POWER"P3V3_AUX"
CDS_LIB"logical_power";
"A"7;
%"Q_RES"
"1","(1075,7075)","0","pure_quanta","I237";
;
PART_NUMBER"CS03322FB03"
MATERIAL"CHIP"
PACK_TYPE"0402LF"
VALUE"33.2"
TOLERANCE"1%"
$LOCATION"R4618"
CDS_LIB"pure_quanta"
WATTAGE"1/16W"
CDS_LOCATION"R4618"
$SEC"1"
CDS_SEC"1";
"B"
$PN"2"51;
"A"
$PN"1"58;
%"Q_RES"
"1","(-1875,7225)","0","pure_quanta","I238";
;
PART_NUMBER"CS03322FB03"
PACK_TYPE"0402LF"
TOLERANCE"1%"
VALUE"33.2"
MATERIAL"CHIP"
LOCATION"R4614"
CDS_LIB"pure_quanta"
WATTAGE"1/16W"
$SEC"1"
CDS_SEC"1";
"B"
$PN"2"73;
"A"
$PN"1"48;
%"UNIVERSAL_POWER"
"1","(1475,6275)","0","logical_power","I240";
;
HDL_POWER"P3V3_AUX"
CDS_LIB"logical_power";
"A"6;
%"Q_CAP"
"1","(1475,6000)","0","pure_quanta","I241";
;
PART_NUMBER"CH4104K1B00"
VALUE"0.1UF"
VOLTAGE"25V"
MATERIAL"X7R"
TOLERANCE"10%"
PACK_TYPE"0402"
$LOCATION"C2376"
CDS_LIB"pure_quanta"
CDS_LOCATION"C2376"
$SEC"1"
CDS_SEC"1";
"B"
$PN"2"12;
"A"
$PN"1"6;
%"UNIVERSAL_GND"
"1","(1475,5775)","0","logical_power","I242";
;
HDL_POWER"GND"
CDS_LIB"logical_power";
"A"12;
%"74LVC1G08W57"
"1","(875,5750)","0","pure_quanta","I243";
;
PART_NUMBER"AL1G0008020"
MATERIAL"IC"
VALUE"74LVC1G08W5-7"
PART_TYPE"SMLF"
$LOCATION"U334"
CDS_LIB"pure_quanta"
NEEDS_NO_SIZE"TRUE"
CDS_LMAN_SYM_OUTLINE"-150,150,150,-150"
CDS_LOCATION"U334"
$SEC"1"
CDS_SEC"1";
"VCC"
$PN"5"6;
"Y"
$PN"4"44;
"GND"
$PN"3"13;
"B"
$PN"2"43;
"A"
$PN"1"45;
%"UNIVERSAL_GND"
"1","(525,5525)","0","logical_power","I244";
;
CDS_LIB"logical_power"
HDL_POWER"GND";
"A"13;
%"Q_RES"
"1","(-625,5850)","0","pure_quanta","I245";
;
PART_NUMBER"CS03322FB03"
PACK_TYPE"0402LF"
MATERIAL"CHIP"
VALUE"33.2"
TOLERANCE"1%"
$LOCATION"R4746"
WATTAGE"1/16W"
CDS_LIB"pure_quanta"
CDS_LOCATION"R4746"
$SEC"1"
CDS_SEC"1";
"B"
$PN"2"45;
"A"
$PN"1"50;
%"Q_RES"
"1","(2100,5700)","0","pure_quanta","I247";
;
PART_NUMBER"CS04992FB07"
VALUE"49.9"
MATERIAL"CHIP"
$LOCATION"R4750"
WATTAGE"1/16W"
TOLERANCE"1%"
PACK_TYPE"0402LF"
CDS_LIB"pure_quanta"
CDS_LOCATION"R4750"
$SEC"1"
CDS_SEC"1";
"B"
$PN"2"52;
"A"
$PN"1"44;
%"Q_RES"
"1","(-625,5750)","0","pure_quanta","I249";
;
PART_NUMBER"CS03322FB03"
MATERIAL"CHIP"
VALUE"33.2"
TOLERANCE"1%"
PACK_TYPE"0402LF"
$LOCATION"R4747"
CDS_LIB"pure_quanta"
WATTAGE"1/16W"
CDS_LOCATION"R4747"
$SEC"1"
CDS_SEC"1";
"B"
$PN"2"43;
"A"
$PN"1"49;
%"Q_RES"
"1","(1050,6450)","0","pure_quanta","I253";
;
PART_NUMBER"CS00002JB13"
PACK_TYPE"0402LF"
MATERIAL"EMPTY"
VALUE"0"
TOLERANCE"5%"
$LOCATION"R4748"
CDS_LIB"pure_quanta"
WATTAGE"1/16W"
CDS_LOCATION"R4748"
$SEC"1"
CDS_SEC"1";
"B"
$PN"2"44;
"A"
$PN"1"45;
%"Q_RES"
"1","(1100,5375)","0","pure_quanta","I254";
;
PART_NUMBER"CS00002JB13"
MATERIAL"EMPTY"
TOLERANCE"5%"
PACK_TYPE"0402LF"
VALUE"0"
$LOCATION"R4749"
CDS_LIB"pure_quanta"
WATTAGE"1/16W"
CDS_LOCATION"R4749"
$SEC"1"
CDS_SEC"1";
"B"
$PN"2"44;
"A"
$PN"1"43;
%"UNIVERSAL_POWER"
"1","(-350,6400)","0","logical_power","I255";
;
HDL_POWER"P3V3_AUX"
CDS_LIB"logical_power";
"A"3;
%"Q_RES"
"2","(-350,6200)","0","pure_quanta","I256";
;
PART_NUMBER"CS31002FB08"
WATTAGE"1/16W"
TOLERANCE"1%"
MATERIAL"CHIP"
PACK_TYPE"0402LF"
VALUE"10K"
$LOCATION"R4745"
CDS_LIB"pure_quanta"
CDS_LOCATION"R4745"
$SEC"1"
CDS_SEC"1";
"A"
$PN"1"3;
"B"
$PN"2"43;
%"Q_RES"
"2","(-275,9875)","0","pure_quanta","I257";
;
PART_NUMBER"CS31002FB08"
TOLERANCE"1%"
WATTAGE"1/16W"
MATERIAL"CHIP"
PACK_TYPE"0402LF"
VALUE"10K"
$LOCATION"R4764"
CDS_LIB"pure_quanta"
CDS_LOCATION"R4764"
$SEC"1"
CDS_SEC"1";
"A"
$PN"1"1;
"B"
$PN"2"28;
%"UNIVERSAL_POWER"
"1","(-275,10100)","0","logical_power","I258";
;
HDL_POWER"P3V3_AUX"
CDS_LIB"logical_power";
"A"1;
END.
